# T6G (Grand Teton) — schematic netlist excerpt (pin names and nets, part order shuffled) for the footprints in the layout excerpt that follows; sources: Cadence DE-HDL packaged netlist, KiCad conversion of 04192023_DAF0TMB3IC0_F0TG_MB_C_brd_V02_OCP.brd

R6790  Q_RES  1K 1% CHIP  pkg 0201LF  page 344 : A = U20_E2 ; B = GND
PR136  Q_RES  5.6 1% CHIP  pkg 0402LF  page 208 : A = SW_PVDD11_S3_P0_BOOT2 ; B = SW_PVDD11_S3_P0_BOOT2_RC
R6167  Q_RES  1K 1% EMPTY  pkg 0402LF  page 112 : A = P3V3_AUX ; B = FM_P2E_BUF2_VODB_DB

(kicad_pcb
	(version 20260206)
	(generator "pcbnew")
	(generator_version "10.0")
	(general
		(thickness 1.6)
		(legacy_teardrops no)
	)
	(paper "A4")
	(title_block
		(title "04192023_DAF0TMB3IC0_F0TG_MB_C_brd_V02_OCP.brd")
		(comment 1 "Grand Teton / footprints 819-821 of 8354")
	)
	(layers
		(0 "F.Cu" signal "TOP")
		(4 "In1.Cu" signal "GND")
		(6 "In2.Cu" signal "IN1")
		(8 "In3.Cu" signal "GND1")
		(10 "In4.Cu" signal "IN2")
		(12 "In5.Cu" signal "GND2")
		(14 "In6.Cu" signal "IN3")
		(16 "In7.Cu" signal "GND3")
		(18 "In8.Cu" signal "VCC")
		(20 "In9.Cu" signal "VCC1")
		(22 "In10.Cu" signal "GND4")
		(24 "In11.Cu" signal "IN4")
		(26 "In12.Cu" signal "GND5")
		(28 "In13.Cu" signal "IN5")
		(30 "In14.Cu" signal "GND6")
		(32 "In15.Cu" signal "IN6")
		(34 "In16.Cu" signal "GND7")
		(2 "B.Cu" signal "BOTTOM")
		(9 "F.Adhes" user "F.Adhesive")
		(11 "B.Adhes" user "B.Adhesive")
		(13 "F.Paste" user "Package Geometry/Pastemask Top")
		(15 "B.Paste" user "Package Geometry/Pastemask Bottom")
		(5 "F.SilkS" user "Ref Des/Silkscreen Top")
		(7 "B.SilkS" user "Ref Des/Silkscreen Bottom")
		(1 "F.Mask" user "Board Geometry/Soldermask Top")
		(3 "B.Mask" user "Board Geometry/Soldermask Bottom")
		(17 "Dwgs.User" user "User.Drawings")
		(19 "Cmts.User" user "User.Comments")
		(21 "Eco1.User" user "User.Eco1")
		(23 "Eco2.User" user "User.Eco2")
		(25 "Edge.Cuts" user "Board Geometry/Outline")
		(27 "Margin" user)
		(31 "F.CrtYd" user "Package Geometry/Place Bound Top")
		(29 "B.CrtYd" user "Package Geometry/Place Bound Bottom")
		(35 "F.Fab" user "Ref Des/Assembly Top")
		(33 "B.Fab" user "Ref Des/Assembly Bottom")
	)
	(footprint ""
		(layer "F.Cu")
		(at 432.729894 -355.743764 90)
		(property "Reference" "PR136"
			(at 0 0 90)
			(layer "F.SilkS")
			(hide yes)
			(effects
				(font
					(size 1.27 1.27)
				)
			)
		)
		(property "Value" ""
			(at 0 0 90)
			(layer "F.Fab")
			(effects
				(font
					(size 1.27 1.27)
				)
			)
		)
		(duplicate_pad_numbers_are_jumpers no)
		(fp_line
			(start 0.7874 -0.4064)
			(end 0.7874 0.4064)
			(stroke
				(width 0.1524)
				(type default)
			)
			(layer "F.SilkS")
		)
		(fp_line
			(start -0.7874 -0.4064)
			(end 0.7874 -0.4064)
			(stroke
				(width 0.1524)
				(type default)
			)
			(layer "F.SilkS")
		)
		(fp_line
			(start 0.7874 0.4064)
			(end -0.7874 0.4064)
			(stroke
				(width 0.1524)
				(type default)
			)
			(layer "F.SilkS")
		)
		(fp_line
			(start -0.7874 0.4064)
			(end -0.7874 -0.4064)
			(stroke
				(width 0.1524)
				(type default)
			)
			(layer "F.SilkS")
		)
		(fp_line
			(start -0.12065 -0.305054)
			(end -0.12065 -0.2794)
			(stroke
				(width 0.1)
				(type default)
			)
			(layer "F.Fab")
		)
		(fp_line
			(start -0.67945 -0.305054)
			(end -0.12065 -0.305054)
			(stroke
				(width 0.1)
				(type default)
			)
			(layer "F.Fab")
		)
		(fp_line
			(start 0.67945 -0.3048)
			(end 0.67945 0.3048)
			(stroke
				(width 0.1)
				(type default)
			)
			(layer "F.Fab")
		)
		(fp_line
			(start 0.12065 -0.3048)
			(end 0.67945 -0.3048)
			(stroke
				(width 0.1)
				(type default)
			)
			(layer "F.Fab")
		)
		(fp_line
			(start 0.12065 -0.2794)
			(end 0.12065 -0.3048)
			(stroke
				(width 0.1)
				(type default)
			)
			(layer "F.Fab")
		)
		(fp_line
			(start -0.12065 -0.2794)
			(end 0.12065 -0.2794)
			(stroke
				(width 0.1)
				(type default)
			)
			(layer "F.Fab")
		)
		(fp_line
			(start 0.120396 0.2794)
			(end -0.12065 0.2794)
			(stroke
				(width 0.1)
				(type default)
			)
			(layer "F.Fab")
		)
		(fp_line
			(start -0.12065 0.2794)
			(end -0.12065 0.3048)
			(stroke
				(width 0.1)
				(type default)
			)
			(layer "F.Fab")
		)
		(fp_line
			(start 0.67945 0.3048)
			(end 0.120396 0.3048)
			(stroke
				(width 0.1)
				(type default)
			)
			(layer "F.Fab")
		)
		(fp_line
			(start 0.120396 0.3048)
			(end 0.120396 0.2794)
			(stroke
				(width 0.1)
				(type default)
			)
			(layer "F.Fab")
		)
		(fp_line
			(start -0.12065 0.3048)
			(end -0.67945 0.3048)
			(stroke
				(width 0.1)
				(type default)
			)
			(layer "F.Fab")
		)
		(fp_line
			(start -0.67945 0.3048)
			(end -0.67945 -0.305054)
			(stroke
				(width 0.1)
				(type default)
			)
			(layer "F.Fab")
		)
		(pad "1" smd circle
			(at -0.40005 0 90)
			(size 0 0)
			(layers "F.Cu" "F.Mask" "F.Paste")
			(net "SW_PVDD11_S3_P0_BOOT2")
		)
		(pad "2" smd circle
			(at 0.40005 0 90)
			(size 0 0)
			(layers "F.Cu" "F.Mask" "F.Paste")
			(net "SW_PVDD11_S3_P0_BOOT2_RC")
		)
	)
	(footprint ""
		(layer "F.Cu")
		(at 15.399258 -427.232064 180)
		(property "Reference" "R6167"
			(at 0 0 180)
			(layer "F.SilkS")
			(hide yes)
			(effects
				(font
					(size 1.27 1.27)
				)
			)
		)
		(property "Value" ""
			(at 0 0 180)
			(layer "F.Fab")
			(effects
				(font
					(size 1.27 1.27)
				)
			)
		)
		(duplicate_pad_numbers_are_jumpers no)
		(fp_line
			(start 0.7874 0.4064)
			(end -0.7874 0.4064)
			(stroke
				(width 0.1524)
				(type default)
			)
			(layer "F.SilkS")
		)
		(fp_line
			(start 0.7874 -0.4064)
			(end 0.7874 0.4064)
			(stroke
				(width 0.1524)
				(type default)
			)
			(layer "F.SilkS")
		)
		(fp_line
			(start -0.7874 0.4064)
			(end -0.7874 -0.4064)
			(stroke
				(width 0.1524)
				(type default)
			)
			(layer "F.SilkS")
		)
		(fp_line
			(start -0.7874 -0.4064)
			(end 0.7874 -0.4064)
			(stroke
				(width 0.1524)
				(type default)
			)
			(layer "F.SilkS")
		)
		(fp_line
			(start 0.67945 0.3048)
			(end 0.120396 0.3048)
			(stroke
				(width 0.1)
				(type default)
			)
			(layer "F.Fab")
		)
		(fp_line
			(start 0.67945 -0.3048)
			(end 0.67945 0.3048)
			(stroke
				(width 0.1)
				(type default)
			)
			(layer "F.Fab")
		)
		(fp_line
			(start 0.12065 -0.2794)
			(end 0.12065 -0.3048)
			(stroke
				(width 0.1)
				(type default)
			)
			(layer "F.Fab")
		)
		(fp_line
			(start 0.12065 -0.3048)
			(end 0.67945 -0.3048)
			(stroke
				(width 0.1)
				(type default)
			)
			(layer "F.Fab")
		)
		(fp_line
			(start 0.120396 0.3048)
			(end 0.120396 0.2794)
			(stroke
				(width 0.1)
				(type default)
			)
			(layer "F.Fab")
		)
		(fp_line
			(start 0.120396 0.2794)
			(end -0.12065 0.2794)
			(stroke
				(width 0.1)
				(type default)
			)
			(layer "F.Fab")
		)
		(fp_line
			(start -0.12065 0.3048)
			(end -0.67945 0.3048)
			(stroke
				(width 0.1)
				(type default)
			)
			(layer "F.Fab")
		)
		(fp_line
			(start -0.12065 0.2794)
			(end -0.12065 0.3048)
			(stroke
				(width 0.1)
				(type default)
			)
			(layer "F.Fab")
		)
		(fp_line
			(start -0.12065 -0.2794)
			(end 0.12065 -0.2794)
			(stroke
				(width 0.1)
				(type default)
			)
			(layer "F.Fab")
		)
		(fp_line
			(start -0.12065 -0.305054)
			(end -0.12065 -0.2794)
			(stroke
				(width 0.1)
				(type default)
			)
			(layer "F.Fab")
		)
		(fp_line
			(start -0.67945 0.3048)
			(end -0.67945 -0.305054)
			(stroke
				(width 0.1)
				(type default)
			)
			(layer "F.Fab")
		)
		(fp_line
			(start -0.67945 -0.305054)
			(end -0.12065 -0.305054)
			(stroke
				(width 0.1)
				(type default)
			)
			(layer "F.Fab")
		)
		(pad "1" smd circle
			(at -0.40005 0 180)
			(size 0 0)
			(layers "F.Cu" "F.Mask" "F.Paste")
			(net "P3V3_AUX")
		)
		(pad "2" smd circle
			(at 0.40005 0 180)
			(size 0 0)
			(layers "F.Cu" "F.Mask" "F.Paste")
			(net "FM_P2E_BUF2_VODB_DB")
		)
	)
	(footprint ""
		(layer "F.Cu")
		(at 163.17087 -428.23638 180)
		(property "Reference" "R6790"
			(at 0 0 180)
			(layer "F.SilkS")
			(hide yes)
			(effects
				(font
					(size 1.27 1.27)
				)
			)
		)
		(property "Value" ""
			(at 0 0 180)
			(layer "F.Fab")
			(effects
				(font
					(size 1.27 1.27)
				)
			)
		)
		(duplicate_pad_numbers_are_jumpers no)
		(fp_line
			(start 0.32512 0.175006)
			(end -0.32512 0.175006)
			(stroke
				(width 0.1)
				(type default)
			)
			(layer "F.Fab")
		)
		(fp_line
			(start 0.32512 -0.175006)
			(end 0.32512 0.175006)
			(stroke
				(width 0.1)
				(type default)
			)
			(layer "F.Fab")
		)
		(fp_line
			(start -0.32512 0.175006)
			(end -0.32512 -0.175006)
			(stroke
				(width 0.1)
				(type default)
			)
			(layer "F.Fab")
		)
		(fp_line
			(start -0.32512 -0.175006)
			(end 0.32512 -0.175006)
			(stroke
				(width 0.1)
				(type default)
			)
			(layer "F.Fab")
		)
		(pad "1" smd rect
			(at -0.2667 0 180)
			(size 0.3048 0.381)
			(layers "F.Cu" "F.Mask" "F.Paste")
			(net "U20_E2")
		)
		(pad "2" smd rect
			(at 0.2667 0)
			(size 0.3048 0.381)
			(layers "F.Cu" "F.Mask" "F.Paste")
			(net "GND")
		)
	)
)
